# T6G (Grand Teton) — schematic netlist excerpt (pin names and nets, part order shuffled) for the footprints in the layout excerpt that follows; sources: Cadence DE-HDL packaged netlist, KiCad conversion of 04192023_DAF0TMB3IC0_F0TG_MB_C_brd_V02_OCP.brd

Q119  MOSFET_NCH_DUAL  PJT138K IC  pkg SOT363XD  page 140
  S1  = GND
  G1  = P3V3_OCP_EN_2_R
  D2  = P3V3_OCP_UV_2_R1
  S2  = GND
  G2  = P3V3_OCP_2_EN_G
  D1  = P3V3_OCP_2_EN_G

R3355  Q_RES  0 5% CHIP  pkg 0402LF  page 55 : A = CLK_100M_CPU1_CLK01_R_DN ; B = CLK_100M_CPU1_CLK01_DN

(kicad_pcb
	(version 20260206)
	(generator "pcbnew")
	(generator_version "10.0")
	(general
		(thickness 1.6)
		(legacy_teardrops no)
	)
	(paper "A4")
	(title_block
		(title "04192023_DAF0TMB3IC0_F0TG_MB_C_brd_V02_OCP.brd")
		(comment 1 "Grand Teton / footprints 2756-2757 of 8354")
	)
	(layers
		(0 "F.Cu" signal "TOP")
		(4 "In1.Cu" signal "GND")
		(6 "In2.Cu" signal "IN1")
		(8 "In3.Cu" signal "GND1")
		(10 "In4.Cu" signal "IN2")
		(12 "In5.Cu" signal "GND2")
		(14 "In6.Cu" signal "IN3")
		(16 "In7.Cu" signal "GND3")
		(18 "In8.Cu" signal "VCC")
		(20 "In9.Cu" signal "VCC1")
		(22 "In10.Cu" signal "GND4")
		(24 "In11.Cu" signal "IN4")
		(26 "In12.Cu" signal "GND5")
		(28 "In13.Cu" signal "IN5")
		(30 "In14.Cu" signal "GND6")
		(32 "In15.Cu" signal "IN6")
		(34 "In16.Cu" signal "GND7")
		(2 "B.Cu" signal "BOTTOM")
		(9 "F.Adhes" user "F.Adhesive")
		(11 "B.Adhes" user "B.Adhesive")
		(13 "F.Paste" user "Package Geometry/Pastemask Top")
		(15 "B.Paste" user "Package Geometry/Pastemask Bottom")
		(5 "F.SilkS" user "Ref Des/Silkscreen Top")
		(7 "B.SilkS" user "Ref Des/Silkscreen Bottom")
		(1 "F.Mask" user "Board Geometry/Soldermask Top")
		(3 "B.Mask" user "Board Geometry/Soldermask Bottom")
		(17 "Dwgs.User" user "User.Drawings")
		(19 "Cmts.User" user "User.Comments")
		(21 "Eco1.User" user "User.Eco1")
		(23 "Eco2.User" user "User.Eco2")
		(25 "Edge.Cuts" user "Board Geometry/Outline")
		(27 "Margin" user)
		(31 "F.CrtYd" user "Package Geometry/Place Bound Top")
		(29 "B.CrtYd" user "Package Geometry/Place Bound Bottom")
		(35 "F.Fab" user "Ref Des/Assembly Top")
		(33 "B.Fab" user "Ref Des/Assembly Bottom")
	)
	(footprint ""
		(layer "F.Cu")
		(at 62.48273 -40.031162)
		(property "Reference" "Q119"
			(at -1.424432 -2.13614 0)
			(unlocked yes)
			(layer "F.SilkS")
			(effects
				(font
					(size 0.7874 0.5842)
					(thickness 0.1524)
				)
				(justify left)
			)
		)
		(property "Value" ""
			(at 0 0 0)
			(layer "F.Fab")
			(effects
				(font
					(size 1.27 1.27)
				)
			)
		)
		(duplicate_pad_numbers_are_jumpers no)
		(fp_line
			(start -1.332738 -1.100074)
			(end -0.4826 -1.100074)
			(stroke
				(width 0.1524)
				(type default)
			)
			(layer "F.SilkS")
		)
		(fp_line
			(start -1.332738 1.100074)
			(end -1.332738 -1.100074)
			(stroke
				(width 0.1524)
				(type default)
			)
			(layer "F.SilkS")
		)
		(fp_line
			(start -0.4826 -1.100074)
			(end 0 -0.541274)
			(stroke
				(width 0.1524)
				(type default)
			)
			(layer "F.SilkS")
		)
		(fp_line
			(start 0 -0.541274)
			(end 0.4826 -1.100074)
			(stroke
				(width 0.1524)
				(type default)
			)
			(layer "F.SilkS")
		)
		(fp_line
			(start 0.4826 -1.100074)
			(end 1.332738 -1.100074)
			(stroke
				(width 0.1524)
				(type default)
			)
			(layer "F.SilkS")
		)
		(fp_line
			(start 1.332738 -1.100074)
			(end 1.332738 1.100074)
			(stroke
				(width 0.1524)
				(type default)
			)
			(layer "F.SilkS")
		)
		(fp_line
			(start 1.332738 1.100074)
			(end -1.332738 1.100074)
			(stroke
				(width 0.1524)
				(type default)
			)
			(layer "F.SilkS")
		)
		(fp_poly
			(pts
				(xy -1.533144 -0.649986) (xy -2.2352 -0.298958) (xy -2.2352 -1.001014)
			)
			(stroke
				(width 0)
				(type default)
			)
			(fill yes)
			(layer "F.SilkS")
		)
		(fp_line
			(start -0.674878 -1.100074)
			(end 0.674878 -1.100074)
			(stroke
				(width 0.1)
				(type default)
			)
			(layer "F.Fab")
		)
		(fp_line
			(start -0.674878 1.100074)
			(end -0.674878 -1.100074)
			(stroke
				(width 0.1)
				(type default)
			)
			(layer "F.Fab")
		)
		(fp_line
			(start 0.674878 -1.100074)
			(end 0.674878 1.100074)
			(stroke
				(width 0.1)
				(type default)
			)
			(layer "F.Fab")
		)
		(fp_line
			(start 0.674878 1.100074)
			(end -0.674878 1.100074)
			(stroke
				(width 0.1)
				(type default)
			)
			(layer "F.Fab")
		)
		(fp_poly
			(pts
				(xy -2.2352 -0.298958) (xy -2.2352 -1.001014) (xy -1.533144 -0.649986)
			)
			(stroke
				(width 0)
				(type default)
			)
			(fill yes)
			(layer "F.Fab")
		)
		(pad "1" smd rect
			(at -0.94996 -0.649986 90)
			(size 0.4318 0.508)
			(layers "F.Cu" "F.Mask" "F.Paste")
			(net "GND")
		)
		(pad "2" smd rect
			(at -0.94996 0 90)
			(size 0.4318 0.508)
			(layers "F.Cu" "F.Mask" "F.Paste")
			(net "P3V3_OCP_EN_2_R")
		)
		(pad "3" smd rect
			(at -0.94996 0.649986 90)
			(size 0.4318 0.508)
			(layers "F.Cu" "F.Mask" "F.Paste")
			(net "P3V3_OCP_UV_2_R1")
		)
		(pad "4" smd rect
			(at 0.94996 0.649986 90)
			(size 0.4318 0.508)
			(layers "F.Cu" "F.Mask" "F.Paste")
			(net "GND")
		)
		(pad "5" smd rect
			(at 0.94996 0 90)
			(size 0.4318 0.508)
			(layers "F.Cu" "F.Mask" "F.Paste")
			(net "P3V3_OCP_2_EN_G")
		)
		(pad "6" smd rect
			(at 0.94996 -0.649986 90)
			(size 0.4318 0.508)
			(layers "F.Cu" "F.Mask" "F.Paste")
			(net "P3V3_OCP_2_EN_G")
		)
	)
	(footprint ""
		(layer "F.Cu")
		(at 154.293824 -191.358266 -90)
		(property "Reference" "R3355"
			(at 0 0 270)
			(layer "F.SilkS")
			(hide yes)
			(effects
				(font
					(size 1.27 1.27)
				)
			)
		)
		(property "Value" ""
			(at 0 0 270)
			(layer "F.Fab")
			(effects
				(font
					(size 1.27 1.27)
				)
			)
		)
		(duplicate_pad_numbers_are_jumpers no)
		(fp_line
			(start 0.324866 0.4064)
			(end -0.386334 0.4064)
			(stroke
				(width 0.1524)
				(type default)
			)
			(layer "F.SilkS")
		)
		(fp_line
			(start -0.7874 -0.011176)
			(end -0.7874 -0.4064)
			(stroke
				(width 0.1524)
				(type default)
			)
			(layer "F.SilkS")
		)
		(fp_line
			(start -0.7874 -0.4064)
			(end 0.7874 -0.4064)
			(stroke
				(width 0.1524)
				(type default)
			)
			(layer "F.SilkS")
		)
		(fp_line
			(start 0.7874 -0.4064)
			(end 0.7874 -0.011176)
			(stroke
				(width 0.1524)
				(type default)
			)
			(layer "F.SilkS")
		)
		(fp_line
			(start -0.67945 0.3048)
			(end -0.67945 -0.305054)
			(stroke
				(width 0.1)
				(type default)
			)
			(layer "F.Fab")
		)
		(fp_line
			(start -0.12065 0.3048)
			(end -0.67945 0.3048)
			(stroke
				(width 0.1)
				(type default)
			)
			(layer "F.Fab")
		)
		(fp_line
			(start 0.120396 0.3048)
			(end 0.120396 0.2794)
			(stroke
				(width 0.1)
				(type default)
			)
			(layer "F.Fab")
		)
		(fp_line
			(start 0.67945 0.3048)
			(end 0.120396 0.3048)
			(stroke
				(width 0.1)
				(type default)
			)
			(layer "F.Fab")
		)
		(fp_line
			(start -0.12065 0.2794)
			(end -0.12065 0.3048)
			(stroke
				(width 0.1)
				(type default)
			)
			(layer "F.Fab")
		)
		(fp_line
			(start 0.120396 0.2794)
			(end -0.12065 0.2794)
			(stroke
				(width 0.1)
				(type default)
			)
			(layer "F.Fab")
		)
		(fp_line
			(start -0.12065 -0.2794)
			(end 0.12065 -0.2794)
			(stroke
				(width 0.1)
				(type default)
			)
			(layer "F.Fab")
		)
		(fp_line
			(start 0.12065 -0.2794)
			(end 0.12065 -0.3048)
			(stroke
				(width 0.1)
				(type default)
			)
			(layer "F.Fab")
		)
		(fp_line
			(start 0.12065 -0.3048)
			(end 0.67945 -0.3048)
			(stroke
				(width 0.1)
				(type default)
			)
			(layer "F.Fab")
		)
		(fp_line
			(start 0.67945 -0.3048)
			(end 0.67945 0.3048)
			(stroke
				(width 0.1)
				(type default)
			)
			(layer "F.Fab")
		)
		(fp_line
			(start -0.67945 -0.305054)
			(end -0.12065 -0.305054)
			(stroke
				(width 0.1)
				(type default)
			)
			(layer "F.Fab")
		)
		(fp_line
			(start -0.12065 -0.305054)
			(end -0.12065 -0.2794)
			(stroke
				(width 0.1)
				(type default)
			)
			(layer "F.Fab")
		)
		(pad "1" smd circle
			(at -0.40005 0 270)
			(size 0 0)
			(layers "F.Cu" "F.Mask" "F.Paste")
			(net "CLK_100M_CPU1_CLK01_R_DN")
		)
		(pad "2" smd circle
			(at 0.40005 0 270)
			(size 0 0)
			(layers "F.Cu" "F.Mask" "F.Paste")
			(net "CLK_100M_CPU1_CLK01_DN")
		)
	)
)
